# S9S_MB_2U (Grand Teton) — schematic netlist excerpt (pin names and nets, part order shuffled) for the footprints in the layout excerpt that follows; sources: Cadence DE-HDL packaged netlist, KiCad conversion of 03242023_DA0F0TMBIJ0_F0T_Motherboard_J_brd_V01_OCP.brd

C383  Q_CAP  47UF 4V 20% X6S  pkg C0805  page 76 : A = PVCCIN_CPU0 ; B = GND
C354  Q_CAP  47UF 4V 20% X6S  pkg C0805  page 79 : A = PVCCIN_CPU1 ; B = GND
C528  Q_CAP  47UF 4V 20% X6S  pkg C0805  page 76 : A = PVCCINFAON_CPU0 ; B = GND

(kicad_pcb
	(version 20260206)
	(generator "pcbnew")
	(generator_version "10.0")
	(general
		(thickness 1.6)
		(legacy_teardrops no)
	)
	(paper "A4")
	(title_block
		(title "03242023_DA0F0TMBIJ0_F0T_Motherboard_J_brd_V01_OCP.brd")
		(comment 1 "Grand Teton / footprints 5479-5481 of 6105")
	)
	(layers
		(0 "F.Cu" signal "TOP")
		(4 "In1.Cu" signal "GND")
		(6 "In2.Cu" signal "IN1")
		(8 "In3.Cu" signal "GND1")
		(10 "In4.Cu" signal "IN2")
		(12 "In5.Cu" signal "GND2")
		(14 "In6.Cu" signal "IN3")
		(16 "In7.Cu" signal "GND3")
		(18 "In8.Cu" signal "VCC")
		(20 "In9.Cu" signal "VCC1")
		(22 "In10.Cu" signal "GND4")
		(24 "In11.Cu" signal "IN4")
		(26 "In12.Cu" signal "GND5")
		(28 "In13.Cu" signal "IN5")
		(30 "In14.Cu" signal "GND6")
		(32 "In15.Cu" signal "IN6")
		(34 "In16.Cu" signal "GND7")
		(2 "B.Cu" signal "BOTTOM")
		(9 "F.Adhes" user "F.Adhesive")
		(11 "B.Adhes" user "B.Adhesive")
		(13 "F.Paste" user "Package Geometry/Pastemask Top")
		(15 "B.Paste" user "Package Geometry/Pastemask Bottom")
		(5 "F.SilkS" user "Ref Des/Silkscreen Top")
		(7 "B.SilkS" user "Ref Des/Silkscreen Bottom")
		(1 "F.Mask" user "Board Geometry/Soldermask Top")
		(3 "B.Mask" user "Board Geometry/Soldermask Bottom")
		(17 "Dwgs.User" user "User.Drawings")
		(19 "Cmts.User" user "User.Comments")
		(21 "Eco1.User" user "User.Eco1")
		(23 "Eco2.User" user "User.Eco2")
		(25 "Edge.Cuts" user "Board Geometry/Outline")
		(27 "Margin" user)
		(31 "F.CrtYd" user "Package Geometry/Place Bound Top")
		(29 "B.CrtYd" user "Package Geometry/Place Bound Bottom")
		(35 "F.Fab" user "Ref Des/Assembly Top")
		(33 "B.Fab" user "Ref Des/Assembly Bottom")
	)
	(footprint ""
		(layer "B.Cu")
		(at 369.522502 -210.19389 180)
		(property "Reference" "C528"
			(at 0 0 0)
			(layer "B.SilkS")
			(hide yes)
			(effects
				(font
					(size 1.27 1.27)
				)
				(justify mirror)
			)
		)
		(property "Value" ""
			(at 0 0 0)
			(layer "B.Fab")
			(effects
				(font
					(size 1.27 1.27)
				)
				(justify mirror)
			)
		)
		(duplicate_pad_numbers_are_jumpers no)
		(fp_line
			(start 1.524 0.762)
			(end 1.524 -0.762)
			(stroke
				(width 0.1524)
				(type default)
			)
			(layer "B.SilkS")
		)
		(fp_line
			(start 1.524 -0.762)
			(end -1.524 -0.762)
			(stroke
				(width 0.1524)
				(type default)
			)
			(layer "B.SilkS")
		)
		(fp_line
			(start -1.524 0.762)
			(end 1.524 0.762)
			(stroke
				(width 0.1524)
				(type default)
			)
			(layer "B.SilkS")
		)
		(fp_line
			(start -1.524 -0.762)
			(end -1.524 0.762)
			(stroke
				(width 0.1524)
				(type default)
			)
			(layer "B.SilkS")
		)
		(fp_line
			(start 1.1049 0.724916)
			(end -1.1049 0.724916)
			(stroke
				(width 0.1)
				(type default)
			)
			(layer "B.Fab")
		)
		(fp_line
			(start 1.1049 -0.724916)
			(end 1.1049 0.724916)
			(stroke
				(width 0.1)
				(type default)
			)
			(layer "B.Fab")
		)
		(fp_line
			(start -1.1049 0.724916)
			(end -1.1049 -0.724916)
			(stroke
				(width 0.1)
				(type default)
			)
			(layer "B.Fab")
		)
		(fp_line
			(start -1.1049 -0.724916)
			(end 1.1049 -0.724916)
			(stroke
				(width 0.1)
				(type default)
			)
			(layer "B.Fab")
		)
		(pad "1" smd rect
			(at 0.889 0 180)
			(size 1.016 1.27)
			(layers "B.Cu" "B.Mask" "B.Paste")
			(net "PVCCINFAON_CPU0")
		)
		(pad "2" smd rect
			(at -0.889 0 180)
			(size 1.016 1.27)
			(layers "B.Cu" "B.Mask" "B.Paste")
			(net "GND")
		)
	)
	(footprint ""
		(layer "B.Cu")
		(at 369.485418 -294.009826 180)
		(property "Reference" "C383"
			(at 0 0 0)
			(layer "B.SilkS")
			(hide yes)
			(effects
				(font
					(size 1.27 1.27)
				)
				(justify mirror)
			)
		)
		(property "Value" ""
			(at 0 0 0)
			(layer "B.Fab")
			(effects
				(font
					(size 1.27 1.27)
				)
				(justify mirror)
			)
		)
		(duplicate_pad_numbers_are_jumpers no)
		(fp_line
			(start 1.524 0.762)
			(end 1.524 -0.762)
			(stroke
				(width 0.1524)
				(type default)
			)
			(layer "B.SilkS")
		)
		(fp_line
			(start 1.524 -0.762)
			(end -1.524 -0.762)
			(stroke
				(width 0.1524)
				(type default)
			)
			(layer "B.SilkS")
		)
		(fp_line
			(start -1.524 0.762)
			(end 1.524 0.762)
			(stroke
				(width 0.1524)
				(type default)
			)
			(layer "B.SilkS")
		)
		(fp_line
			(start -1.524 -0.762)
			(end -1.524 0.762)
			(stroke
				(width 0.1524)
				(type default)
			)
			(layer "B.SilkS")
		)
		(fp_line
			(start 1.1049 0.724916)
			(end -1.1049 0.724916)
			(stroke
				(width 0.1)
				(type default)
			)
			(layer "B.Fab")
		)
		(fp_line
			(start 1.1049 -0.724916)
			(end 1.1049 0.724916)
			(stroke
				(width 0.1)
				(type default)
			)
			(layer "B.Fab")
		)
		(fp_line
			(start -1.1049 0.724916)
			(end -1.1049 -0.724916)
			(stroke
				(width 0.1)
				(type default)
			)
			(layer "B.Fab")
		)
		(fp_line
			(start -1.1049 -0.724916)
			(end 1.1049 -0.724916)
			(stroke
				(width 0.1)
				(type default)
			)
			(layer "B.Fab")
		)
		(pad "1" smd rect
			(at 0.889 0 180)
			(size 1.016 1.27)
			(layers "B.Cu" "B.Mask" "B.Paste")
			(net "PVCCIN_CPU0")
		)
		(pad "2" smd rect
			(at -0.889 0 180)
			(size 1.016 1.27)
			(layers "B.Cu" "B.Mask" "B.Paste")
			(net "GND")
		)
	)
	(footprint ""
		(layer "B.Cu")
		(at 121.545604 -296.05478 180)
		(property "Reference" "C354"
			(at 0 0 0)
			(layer "B.SilkS")
			(hide yes)
			(effects
				(font
					(size 1.27 1.27)
				)
				(justify mirror)
			)
		)
		(property "Value" ""
			(at 0 0 0)
			(layer "B.Fab")
			(effects
				(font
					(size 1.27 1.27)
				)
				(justify mirror)
			)
		)
		(duplicate_pad_numbers_are_jumpers no)
		(fp_line
			(start 1.524 0.762)
			(end 1.524 -0.762)
			(stroke
				(width 0.1524)
				(type default)
			)
			(layer "B.SilkS")
		)
		(fp_line
			(start 1.524 -0.762)
			(end -1.524 -0.762)
			(stroke
				(width 0.1524)
				(type default)
			)
			(layer "B.SilkS")
		)
		(fp_line
			(start -1.524 0.762)
			(end 1.524 0.762)
			(stroke
				(width 0.1524)
				(type default)
			)
			(layer "B.SilkS")
		)
		(fp_line
			(start -1.524 -0.762)
			(end -1.524 0.762)
			(stroke
				(width 0.1524)
				(type default)
			)
			(layer "B.SilkS")
		)
		(fp_line
			(start 1.1049 0.724916)
			(end -1.1049 0.724916)
			(stroke
				(width 0.1)
				(type default)
			)
			(layer "B.Fab")
		)
		(fp_line
			(start 1.1049 -0.724916)
			(end 1.1049 0.724916)
			(stroke
				(width 0.1)
				(type default)
			)
			(layer "B.Fab")
		)
		(fp_line
			(start -1.1049 0.724916)
			(end -1.1049 -0.724916)
			(stroke
				(width 0.1)
				(type default)
			)
			(layer "B.Fab")
		)
		(fp_line
			(start -1.1049 -0.724916)
			(end 1.1049 -0.724916)
			(stroke
				(width 0.1)
				(type default)
			)
			(layer "B.Fab")
		)
		(pad "1" smd rect
			(at 0.889 0 180)
			(size 1.016 1.27)
			(layers "B.Cu" "B.Mask" "B.Paste")
			(net "PVCCIN_CPU1")
		)
		(pad "2" smd rect
			(at -0.889 0 180)
			(size 1.016 1.27)
			(layers "B.Cu" "B.Mask" "B.Paste")
			(net "GND")
		)
	)
)
